# T6G (Grand Teton) — schematic netlist excerpt (pin names and nets, part order shuffled) for the footprints in the layout excerpt that follows; sources: Cadence DE-HDL packaged netlist, KiCad conversion of 04192023_DAF0TMB3IC0_F0TG_MB_C_brd_V02_OCP.brd

R3871  Q_RES  0 5% CHIP  pkg 0402LF  page 135 : A = P12V_OCP_IMON_1 ; B = P12V_OCP_SFF_ISENSE_MPS_MAM
C762  Q_CAP_DIFFBUS  DIFF BUS_0.22UF 6.3V 20% X6S  pkg C0201  page 66 : \1\ = P5E_CPU1_P2_TX_C_DN<5> ; \2\ = P5E_CPU1_P2_TX_DN<5>
R2791  Q_RES  0 5% EMPTY  pkg 0402LF  page 234 : A = USB2_HOST_BMC_B_DN ; B = USB2_HOST_BMC_B_BUF_DN

(kicad_pcb
	(version 20260206)
	(generator "pcbnew")
	(generator_version "10.0")
	(general
		(thickness 1.6)
		(legacy_teardrops no)
	)
	(paper "A4")
	(title_block
		(title "04192023_DAF0TMB3IC0_F0TG_MB_C_brd_V02_OCP.brd")
		(comment 1 "Grand Teton / footprints 4702-4704 of 8354")
	)
	(layers
		(0 "F.Cu" signal "TOP")
		(4 "In1.Cu" signal "GND")
		(6 "In2.Cu" signal "IN1")
		(8 "In3.Cu" signal "GND1")
		(10 "In4.Cu" signal "IN2")
		(12 "In5.Cu" signal "GND2")
		(14 "In6.Cu" signal "IN3")
		(16 "In7.Cu" signal "GND3")
		(18 "In8.Cu" signal "VCC")
		(20 "In9.Cu" signal "VCC1")
		(22 "In10.Cu" signal "GND4")
		(24 "In11.Cu" signal "IN4")
		(26 "In12.Cu" signal "GND5")
		(28 "In13.Cu" signal "IN5")
		(30 "In14.Cu" signal "GND6")
		(32 "In15.Cu" signal "IN6")
		(34 "In16.Cu" signal "GND7")
		(2 "B.Cu" signal "BOTTOM")
		(9 "F.Adhes" user "F.Adhesive")
		(11 "B.Adhes" user "B.Adhesive")
		(13 "F.Paste" user "Package Geometry/Pastemask Top")
		(15 "B.Paste" user "Package Geometry/Pastemask Bottom")
		(5 "F.SilkS" user "Ref Des/Silkscreen Top")
		(7 "B.SilkS" user "Ref Des/Silkscreen Bottom")
		(1 "F.Mask" user "Board Geometry/Soldermask Top")
		(3 "B.Mask" user "Board Geometry/Soldermask Bottom")
		(17 "Dwgs.User" user "User.Drawings")
		(19 "Cmts.User" user "User.Comments")
		(21 "Eco1.User" user "User.Eco1")
		(23 "Eco2.User" user "User.Eco2")
		(25 "Edge.Cuts" user "Board Geometry/Outline")
		(27 "Margin" user)
		(31 "F.CrtYd" user "Package Geometry/Place Bound Top")
		(29 "B.CrtYd" user "Package Geometry/Place Bound Bottom")
		(35 "F.Fab" user "Ref Des/Assembly Top")
		(33 "B.Fab" user "Ref Des/Assembly Bottom")
	)
	(footprint ""
		(layer "F.Cu")
		(at 437.240172 -32.173418 90)
		(property "Reference" "R3871"
			(at 0 0 90)
			(layer "F.SilkS")
			(hide yes)
			(effects
				(font
					(size 1.27 1.27)
				)
			)
		)
		(property "Value" ""
			(at 0 0 90)
			(layer "F.Fab")
			(effects
				(font
					(size 1.27 1.27)
				)
			)
		)
		(duplicate_pad_numbers_are_jumpers no)
		(fp_line
			(start 0.7874 -0.4064)
			(end 0.7874 0.4064)
			(stroke
				(width 0.1524)
				(type default)
			)
			(layer "F.SilkS")
		)
		(fp_line
			(start -0.7874 -0.4064)
			(end 0.7874 -0.4064)
			(stroke
				(width 0.1524)
				(type default)
			)
			(layer "F.SilkS")
		)
		(fp_line
			(start 0.7874 0.4064)
			(end -0.7874 0.4064)
			(stroke
				(width 0.1524)
				(type default)
			)
			(layer "F.SilkS")
		)
		(fp_line
			(start -0.7874 0.4064)
			(end -0.7874 -0.4064)
			(stroke
				(width 0.1524)
				(type default)
			)
			(layer "F.SilkS")
		)
		(fp_line
			(start -0.12065 -0.305054)
			(end -0.12065 -0.2794)
			(stroke
				(width 0.1)
				(type default)
			)
			(layer "F.Fab")
		)
		(fp_line
			(start -0.67945 -0.305054)
			(end -0.12065 -0.305054)
			(stroke
				(width 0.1)
				(type default)
			)
			(layer "F.Fab")
		)
		(fp_line
			(start 0.67945 -0.3048)
			(end 0.67945 0.3048)
			(stroke
				(width 0.1)
				(type default)
			)
			(layer "F.Fab")
		)
		(fp_line
			(start 0.12065 -0.3048)
			(end 0.67945 -0.3048)
			(stroke
				(width 0.1)
				(type default)
			)
			(layer "F.Fab")
		)
		(fp_line
			(start 0.12065 -0.2794)
			(end 0.12065 -0.3048)
			(stroke
				(width 0.1)
				(type default)
			)
			(layer "F.Fab")
		)
		(fp_line
			(start -0.12065 -0.2794)
			(end 0.12065 -0.2794)
			(stroke
				(width 0.1)
				(type default)
			)
			(layer "F.Fab")
		)
		(fp_line
			(start 0.120396 0.2794)
			(end -0.12065 0.2794)
			(stroke
				(width 0.1)
				(type default)
			)
			(layer "F.Fab")
		)
		(fp_line
			(start -0.12065 0.2794)
			(end -0.12065 0.3048)
			(stroke
				(width 0.1)
				(type default)
			)
			(layer "F.Fab")
		)
		(fp_line
			(start 0.67945 0.3048)
			(end 0.120396 0.3048)
			(stroke
				(width 0.1)
				(type default)
			)
			(layer "F.Fab")
		)
		(fp_line
			(start 0.120396 0.3048)
			(end 0.120396 0.2794)
			(stroke
				(width 0.1)
				(type default)
			)
			(layer "F.Fab")
		)
		(fp_line
			(start -0.12065 0.3048)
			(end -0.67945 0.3048)
			(stroke
				(width 0.1)
				(type default)
			)
			(layer "F.Fab")
		)
		(fp_line
			(start -0.67945 0.3048)
			(end -0.67945 -0.305054)
			(stroke
				(width 0.1)
				(type default)
			)
			(layer "F.Fab")
		)
		(pad "1" smd circle
			(at -0.40005 0 90)
			(size 0 0)
			(layers "F.Cu" "F.Mask" "F.Paste")
			(net "P12V_OCP_IMON_1")
		)
		(pad "2" smd circle
			(at 0.40005 0 90)
			(size 0 0)
			(layers "F.Cu" "F.Mask" "F.Paste")
			(net "P12V_OCP_SFF_ISENSE_MPS_MAM")
		)
	)
	(footprint ""
		(layer "F.Cu")
		(at 150.339044 -373.03583 -90)
		(property "Reference" "C762"
			(at 0 0 270)
			(layer "F.SilkS")
			(hide yes)
			(effects
				(font
					(size 1.27 1.27)
				)
			)
		)
		(property "Value" ""
			(at 0 0 270)
			(layer "F.Fab")
			(effects
				(font
					(size 1.27 1.27)
				)
			)
		)
		(duplicate_pad_numbers_are_jumpers no)
		(fp_line
			(start -0.299974 0.150114)
			(end -0.299974 -0.150114)
			(stroke
				(width 0.1)
				(type default)
			)
			(layer "F.Fab")
		)
		(fp_line
			(start 0.299974 0.150114)
			(end -0.299974 0.150114)
			(stroke
				(width 0.1)
				(type default)
			)
			(layer "F.Fab")
		)
		(fp_line
			(start -0.299974 -0.150114)
			(end 0.299974 -0.150114)
			(stroke
				(width 0.1)
				(type default)
			)
			(layer "F.Fab")
		)
		(fp_line
			(start 0.299974 -0.150114)
			(end 0.299974 0.150114)
			(stroke
				(width 0.1)
				(type default)
			)
			(layer "F.Fab")
		)
		(pad "1" smd rect
			(at -0.2667 0 270)
			(size 0.3048 0.381)
			(layers "F.Cu" "F.Mask" "F.Paste")
			(net "P5E_CPU1_P2_TX_C_DN<5>")
		)
		(pad "2" smd rect
			(at 0.2667 0 270)
			(size 0.3048 0.381)
			(layers "F.Cu" "F.Mask" "F.Paste")
			(net "P5E_CPU1_P2_TX_DN<5>")
		)
	)
	(footprint ""
		(layer "F.Cu")
		(at 16.645382 -105.56621 90)
		(property "Reference" "R2791"
			(at 0 0 90)
			(layer "F.SilkS")
			(hide yes)
			(effects
				(font
					(size 1.27 1.27)
				)
			)
		)
		(property "Value" ""
			(at 0 0 90)
			(layer "F.Fab")
			(effects
				(font
					(size 1.27 1.27)
				)
			)
		)
		(duplicate_pad_numbers_are_jumpers no)
		(fp_line
			(start 0.7874 -0.4064)
			(end 0.7874 0.4064)
			(stroke
				(width 0.1524)
				(type default)
			)
			(layer "F.SilkS")
		)
		(fp_line
			(start -0.7874 -0.4064)
			(end 0.7874 -0.4064)
			(stroke
				(width 0.1524)
				(type default)
			)
			(layer "F.SilkS")
		)
		(fp_line
			(start 0.7874 0.4064)
			(end -0.7874 0.4064)
			(stroke
				(width 0.1524)
				(type default)
			)
			(layer "F.SilkS")
		)
		(fp_line
			(start -0.7874 0.4064)
			(end -0.7874 -0.4064)
			(stroke
				(width 0.1524)
				(type default)
			)
			(layer "F.SilkS")
		)
		(fp_line
			(start -0.12065 -0.305054)
			(end -0.12065 -0.2794)
			(stroke
				(width 0.1)
				(type default)
			)
			(layer "F.Fab")
		)
		(fp_line
			(start -0.67945 -0.305054)
			(end -0.12065 -0.305054)
			(stroke
				(width 0.1)
				(type default)
			)
			(layer "F.Fab")
		)
		(fp_line
			(start 0.67945 -0.3048)
			(end 0.67945 0.3048)
			(stroke
				(width 0.1)
				(type default)
			)
			(layer "F.Fab")
		)
		(fp_line
			(start 0.12065 -0.3048)
			(end 0.67945 -0.3048)
			(stroke
				(width 0.1)
				(type default)
			)
			(layer "F.Fab")
		)
		(fp_line
			(start 0.12065 -0.2794)
			(end 0.12065 -0.3048)
			(stroke
				(width 0.1)
				(type default)
			)
			(layer "F.Fab")
		)
		(fp_line
			(start -0.12065 -0.2794)
			(end 0.12065 -0.2794)
			(stroke
				(width 0.1)
				(type default)
			)
			(layer "F.Fab")
		)
		(fp_line
			(start 0.120396 0.2794)
			(end -0.12065 0.2794)
			(stroke
				(width 0.1)
				(type default)
			)
			(layer "F.Fab")
		)
		(fp_line
			(start -0.12065 0.2794)
			(end -0.12065 0.3048)
			(stroke
				(width 0.1)
				(type default)
			)
			(layer "F.Fab")
		)
		(fp_line
			(start 0.67945 0.3048)
			(end 0.120396 0.3048)
			(stroke
				(width 0.1)
				(type default)
			)
			(layer "F.Fab")
		)
		(fp_line
			(start 0.120396 0.3048)
			(end 0.120396 0.2794)
			(stroke
				(width 0.1)
				(type default)
			)
			(layer "F.Fab")
		)
		(fp_line
			(start -0.12065 0.3048)
			(end -0.67945 0.3048)
			(stroke
				(width 0.1)
				(type default)
			)
			(layer "F.Fab")
		)
		(fp_line
			(start -0.67945 0.3048)
			(end -0.67945 -0.305054)
			(stroke
				(width 0.1)
				(type default)
			)
			(layer "F.Fab")
		)
		(pad "1" smd rect
			(at -0.40005 0 270)
			(size 0.4572 0.508)
			(layers "F.Cu" "F.Mask" "F.Paste")
			(net "USB2_HOST_BMC_B_DN")
		)
		(pad "2" smd rect
			(at 0.40005 0 270)
			(size 0.4572 0.508)
			(layers "F.Cu" "F.Mask" "F.Paste")
			(net "USB2_HOST_BMC_B_BUF_DN")
		)
	)
)
